# S9S_MB_2U (Grand Teton) — schematic netlist excerpt (pin names and nets, part order shuffled) for the footprints in the layout excerpt that follows; sources: Cadence DE-HDL packaged netlist, KiCad conversion of 03242023_DA0F0TMBIJ0_F0T_Motherboard_J_brd_V01_OCP.brd

Q126  MOSFET_NCH_DUAL  PJT138K IC  pkg SOT363XD  page 192
  S1  = GND
  G1  = P3V3_E1S_EN_1_R
  D2  = P3V3_E1S_UV_0_R
  S2  = GND
  G2  = P3V3_E1S_0_EN_G
  D1  = P3V3_E1S_0_EN_G

PD109  SCHOTTKY_AC  B340A-13-F IC  pkg D2010XF  page 162 : A = GND ; C = P3V3_OCP_V3_2_R

(kicad_pcb
	(version 20260206)
	(generator "pcbnew")
	(generator_version "10.0")
	(general
		(thickness 1.6)
		(legacy_teardrops no)
	)
	(paper "A4")
	(title_block
		(title "03242023_DA0F0TMBIJ0_F0T_Motherboard_J_brd_V01_OCP.brd")
		(comment 1 "Grand Teton / footprints 3299-3300 of 6105")
	)
	(layers
		(0 "F.Cu" signal "TOP")
		(4 "In1.Cu" signal "GND")
		(6 "In2.Cu" signal "IN1")
		(8 "In3.Cu" signal "GND1")
		(10 "In4.Cu" signal "IN2")
		(12 "In5.Cu" signal "GND2")
		(14 "In6.Cu" signal "IN3")
		(16 "In7.Cu" signal "GND3")
		(18 "In8.Cu" signal "VCC")
		(20 "In9.Cu" signal "VCC1")
		(22 "In10.Cu" signal "GND4")
		(24 "In11.Cu" signal "IN4")
		(26 "In12.Cu" signal "GND5")
		(28 "In13.Cu" signal "IN5")
		(30 "In14.Cu" signal "GND6")
		(32 "In15.Cu" signal "IN6")
		(34 "In16.Cu" signal "GND7")
		(2 "B.Cu" signal "BOTTOM")
		(9 "F.Adhes" user "F.Adhesive")
		(11 "B.Adhes" user "B.Adhesive")
		(13 "F.Paste" user "Package Geometry/Pastemask Top")
		(15 "B.Paste" user "Package Geometry/Pastemask Bottom")
		(5 "F.SilkS" user "Ref Des/Silkscreen Top")
		(7 "B.SilkS" user "Ref Des/Silkscreen Bottom")
		(1 "F.Mask" user "Board Geometry/Soldermask Top")
		(3 "B.Mask" user "Board Geometry/Soldermask Bottom")
		(17 "Dwgs.User" user "User.Drawings")
		(19 "Cmts.User" user "User.Comments")
		(21 "Eco1.User" user "User.Eco1")
		(23 "Eco2.User" user "User.Eco2")
		(25 "Edge.Cuts" user "Board Geometry/Outline")
		(27 "Margin" user)
		(31 "F.CrtYd" user "Package Geometry/Place Bound Top")
		(29 "B.CrtYd" user "Package Geometry/Place Bound Bottom")
		(35 "F.Fab" user "Ref Des/Assembly Top")
		(33 "B.Fab" user "Ref Des/Assembly Bottom")
	)
	(footprint ""
		(layer "F.Cu")
		(at 292.928802 -57.509918 -90)
		(property "Reference" "Q126"
			(at 0.4572 7.436612 0)
			(unlocked yes)
			(layer "F.SilkS")
			(effects
				(font
					(size 0.7874 0.5842)
					(thickness 0.1524)
				)
				(justify left)
			)
		)
		(property "Value" ""
			(at 0 0 270)
			(layer "F.Fab")
			(effects
				(font
					(size 1.27 1.27)
				)
			)
		)
		(duplicate_pad_numbers_are_jumpers no)
		(fp_line
			(start -1.332738 1.100074)
			(end -1.332738 -1.100074)
			(stroke
				(width 0.1524)
				(type default)
			)
			(layer "F.SilkS")
		)
		(fp_line
			(start 1.332738 1.100074)
			(end -1.332738 1.100074)
			(stroke
				(width 0.1524)
				(type default)
			)
			(layer "F.SilkS")
		)
		(fp_line
			(start 0 -0.541274)
			(end 0.4826 -1.100074)
			(stroke
				(width 0.1524)
				(type default)
			)
			(layer "F.SilkS")
		)
		(fp_line
			(start -1.332738 -1.100074)
			(end -0.4826 -1.100074)
			(stroke
				(width 0.1524)
				(type default)
			)
			(layer "F.SilkS")
		)
		(fp_line
			(start -0.4826 -1.100074)
			(end 0 -0.541274)
			(stroke
				(width 0.1524)
				(type default)
			)
			(layer "F.SilkS")
		)
		(fp_line
			(start 0.4826 -1.100074)
			(end 1.332738 -1.100074)
			(stroke
				(width 0.1524)
				(type default)
			)
			(layer "F.SilkS")
		)
		(fp_line
			(start 1.332738 -1.100074)
			(end 1.332738 1.100074)
			(stroke
				(width 0.1524)
				(type default)
			)
			(layer "F.SilkS")
		)
		(fp_poly
			(pts
				(xy -2.2352 -1.001014) (xy -1.533144 -0.649986) (xy -2.2352 -0.298958)
			)
			(stroke
				(width 0)
				(type default)
			)
			(fill yes)
			(layer "F.SilkS")
		)
		(fp_line
			(start -0.674878 1.100074)
			(end -0.674878 -1.100074)
			(stroke
				(width 0.1)
				(type default)
			)
			(layer "F.Fab")
		)
		(fp_line
			(start 0.674878 1.100074)
			(end -0.674878 1.100074)
			(stroke
				(width 0.1)
				(type default)
			)
			(layer "F.Fab")
		)
		(fp_line
			(start -0.674878 -1.100074)
			(end 0.674878 -1.100074)
			(stroke
				(width 0.1)
				(type default)
			)
			(layer "F.Fab")
		)
		(fp_line
			(start 0.674878 -1.100074)
			(end 0.674878 1.100074)
			(stroke
				(width 0.1)
				(type default)
			)
			(layer "F.Fab")
		)
		(fp_poly
			(pts
				(xy -2.2352 -0.298958) (xy -2.2352 -1.001014) (xy -1.533144 -0.649986)
			)
			(stroke
				(width 0)
				(type default)
			)
			(fill yes)
			(layer "F.Fab")
		)
		(pad "1" smd rect
			(at -0.94996 -0.649986)
			(size 0.4318 0.508)
			(layers "F.Cu" "F.Mask" "F.Paste")
			(net "GND")
		)
		(pad "2" smd rect
			(at -0.94996 0)
			(size 0.4318 0.508)
			(layers "F.Cu" "F.Mask" "F.Paste")
			(net "P3V3_E1S_EN_1_R")
		)
		(pad "3" smd rect
			(at -0.94996 0.649986)
			(size 0.4318 0.508)
			(layers "F.Cu" "F.Mask" "F.Paste")
			(net "P3V3_E1S_UV_0_R")
		)
		(pad "4" smd rect
			(at 0.94996 0.649986)
			(size 0.4318 0.508)
			(layers "F.Cu" "F.Mask" "F.Paste")
			(net "GND")
		)
		(pad "5" smd rect
			(at 0.94996 0)
			(size 0.4318 0.508)
			(layers "F.Cu" "F.Mask" "F.Paste")
			(net "P3V3_E1S_0_EN_G")
		)
		(pad "6" smd rect
			(at 0.94996 -0.649986)
			(size 0.4318 0.508)
			(layers "F.Cu" "F.Mask" "F.Paste")
			(net "P3V3_E1S_0_EN_G")
		)
	)
	(footprint ""
		(layer "F.Cu")
		(at 74.593958 -61.883798)
		(property "Reference" "PD109"
			(at 5.9944 -0.462788 0)
			(unlocked yes)
			(layer "F.SilkS")
			(effects
				(font
					(size 0.7874 0.5842)
					(thickness 0.1524)
				)
				(justify left)
			)
		)
		(property "Value" ""
			(at 0 0 0)
			(layer "F.Fab")
			(effects
				(font
					(size 1.27 1.27)
				)
			)
		)
		(duplicate_pad_numbers_are_jumpers no)
		(fp_line
			(start -3.400044 -1.459992)
			(end 4.107942 -1.459992)
			(stroke
				(width 0.1524)
				(type default)
			)
			(layer "F.SilkS")
		)
		(fp_line
			(start -3.400044 1.459992)
			(end -3.400044 -1.459992)
			(stroke
				(width 0.1524)
				(type default)
			)
			(layer "F.SilkS")
		)
		(fp_line
			(start 4.107942 -1.459992)
			(end 4.107942 1.459992)
			(stroke
				(width 0.1524)
				(type default)
			)
			(layer "F.SilkS")
		)
		(fp_line
			(start 4.107942 1.459992)
			(end -3.400044 1.459992)
			(stroke
				(width 0.1524)
				(type default)
			)
			(layer "F.SilkS")
		)
		(fp_rect
			(start 3.308096 1.459992)
			(end 4.107942 -1.459992)
			(stroke
				(width 0)
				(type default)
			)
			(fill yes)
			(layer "F.SilkS")
		)
		(fp_line
			(start -2.29997 -1.459992)
			(end 2.29997 -1.459992)
			(stroke
				(width 0.1)
				(type default)
			)
			(layer "F.Fab")
		)
		(fp_line
			(start -2.29997 1.459992)
			(end -2.29997 -1.459992)
			(stroke
				(width 0.1)
				(type default)
			)
			(layer "F.Fab")
		)
		(fp_line
			(start 2.29997 -1.459992)
			(end 2.29997 1.459992)
			(stroke
				(width 0.1)
				(type default)
			)
			(layer "F.Fab")
		)
		(fp_line
			(start 2.29997 1.459992)
			(end -2.29997 1.459992)
			(stroke
				(width 0.1)
				(type default)
			)
			(layer "F.Fab")
		)
		(fp_text user "+"
			(at -4.876038 -1.1557 0)
			(unlocked yes)
			(layer "F.SilkS")
			(effects
				(font
					(size 1.905 1.4224)
					(thickness 0.1524)
				)
				(justify left)
			)
		)
		(fp_text user "-"
			(at 5.4102 0.29845 180)
			(unlocked yes)
			(layer "F.SilkS")
			(effects
				(font
					(size 1.905 1.4224)
					(thickness 0.1524)
				)
				(justify left)
			)
		)
		(fp_text user "+"
			(at -4.7752 -0.12065 0)
			(unlocked yes)
			(layer "F.Fab")
			(effects
				(font
					(size 1.905 1.4224)
					(thickness 0.1524)
				)
				(justify left)
			)
		)
		(fp_text user "-"
			(at 5.4102 0.29845 180)
			(unlocked yes)
			(layer "F.Fab")
			(effects
				(font
					(size 1.905 1.4224)
					(thickness 0.1524)
				)
				(justify left)
			)
		)
		(pad "A" smd rect
			(at -1.999996 0 90)
			(size 1.7018 2.5146)
			(layers "F.Cu" "F.Mask" "F.Paste")
			(net "GND")
		)
		(pad "C" smd rect
			(at 1.999996 0 90)
			(size 1.7018 2.5146)
			(layers "F.Cu" "F.Mask" "F.Paste")
			(net "P3V3_OCP_V3_2_R")
		)
	)
)
